(kicad_pcb
	(version 20241229)
	(generator "pcbnew")
	(generator_version "9.0")
	(general
		(thickness 1.599998)
		(legacy_teardrops no)
	)
	(paper "A4")
	(title_block
		(title "Artix - Datacenter Secure Control Module (DC-SCM)")
		(date "2024-11-06")
		(rev "1.1.3")
		(comment 9 "footprints 412-418 of 544")
	)
	(layers
		(0 "F.Cu" signal)
		(4 "In1.Cu" signal)
		(6 "In2.Cu" signal)
		(8 "In3.Cu" signal)
		(10 "In4.Cu" signal)
		(12 "In5.Cu" signal)
		(14 "In6.Cu" signal)
		(2 "B.Cu" signal)
		(9 "F.Adhes" user "F.Adhesive")
		(11 "B.Adhes" user "B.Adhesive")
		(13 "F.Paste" user)
		(15 "B.Paste" user)
		(5 "F.SilkS" user "F.Silkscreen")
		(7 "B.SilkS" user "B.Silkscreen")
		(1 "F.Mask" user)
		(3 "B.Mask" user)
		(17 "Dwgs.User" user "User.Drawings")
		(19 "Cmts.User" user "User.Comments")
		(21 "Eco1.User" user "User.Eco1")
		(23 "Eco2.User" user "User.Eco2")
		(25 "Edge.Cuts" user)
		(27 "Margin" user)
		(31 "F.CrtYd" user "F.Courtyard")
		(29 "B.CrtYd" user "B.Courtyard")
		(35 "F.Fab" user)
		(33 "B.Fab" user)
	)
	(footprint "antmicro-footprints:R_0402_1005Metric"
		(layer "B.Cu")
		(at 71.15 126.675 180)
		(descr "Resistor SMD 0402")
		(tags "resistor SMD 0402")
		(property "Reference" "R26"
			(at 0.75 -0.425 0)
			(layer "B.SilkS")
			(effects
				(font
					(size 0.7 0.7)
					(thickness 0.15)
				)
				(justify left bottom mirror)
			)
		)
		(property "Value" "R_1k_0402"
			(at 0 -1.4 0)
			(layer "B.Fab")
			(effects
				(font
					(size 0.7 0.7)
					(thickness 0.15)
				)
				(justify left bottom mirror)
			)
		)
		(property "Datasheet" "https://www.bourns.com/docs/product-datasheets/cr.pdf"
			(at 0 0 180)
			(layer "F.Fab")
			(hide yes)
			(effects
				(font
					(size 1.27 1.27)
					(thickness 0.15)
				)
			)
		)
		(property "Description" "SMD Chip Resistor, 1 kohm, ± 1%, 63 mW, 0402 [1005 Metric], Thick Film, General Purpose"
			(at 0 0 180)
			(layer "F.Fab")
			(hide yes)
			(effects
				(font
					(size 1.27 1.27)
					(thickness 0.15)
				)
			)
		)
		(property "Author" "Antmicro"
			(at 142.3 253.35 0)
			(layer "B.Fab")
			(hide yes)
			(effects
				(font
					(size 1 1)
					(thickness 0.15)
				)
				(justify mirror)
			)
		)
		(property "License" "Apache-2.0"
			(at 142.3 253.35 0)
			(layer "B.Fab")
			(hide yes)
			(effects
				(font
					(size 1 1)
					(thickness 0.15)
				)
				(justify mirror)
			)
		)
		(property "MPN" "CR0402-FX-1001GLF"
			(at 142.3 253.35 0)
			(layer "B.Fab")
			(hide yes)
			(effects
				(font
					(size 1 1)
					(thickness 0.15)
				)
				(justify mirror)
			)
		)
		(property "Manufacturer" "Bourns"
			(at 142.3 253.35 0)
			(layer "B.Fab")
			(hide yes)
			(effects
				(font
					(size 1 1)
					(thickness 0.15)
				)
				(justify mirror)
			)
		)
		(property "Tolerance" "1%"
			(at 142.3 253.35 0)
			(layer "B.Fab")
			(hide yes)
			(effects
				(font
					(size 1 1)
					(thickness 0.15)
				)
				(justify mirror)
			)
		)
		(property "Val" "1k"
			(at 142.3 253.35 0)
			(layer "B.Fab")
			(hide yes)
			(effects
				(font
					(size 1 1)
					(thickness 0.15)
				)
				(justify mirror)
			)
		)
		(sheetname "/RoT/")
		(sheetfile "rot.kicad_sch")
		(attr smd)
		(fp_rect
			(start -0.925 0.47)
			(end 0.925 -0.47)
			(stroke
				(width 0.05)
				(type default)
			)
			(fill no)
			(layer "B.CrtYd")
		)
		(fp_rect
			(start -0.5 0.25)
			(end 0.5 -0.25)
			(stroke
				(width 0.15)
				(type solid)
			)
			(fill no)
			(layer "B.Fab")
		)
		(pad "1" smd roundrect
			(at -0.48 0 180)
			(size 0.59 0.64)
			(layers "B.Cu" "B.Mask" "B.Paste")
			(roundrect_rratio 0.25)
			(net 2 "VCC3V3")
			(pintype "passive")
		)
		(pad "2" smd roundrect
			(at 0.48 0 180)
			(size 0.59 0.64)
			(layers "B.Cu" "B.Mask" "B.Paste")
			(roundrect_rratio 0.25)
			(net 119 "QSPIB_CLK")
			(pintype "passive")
		)
	)
	(footprint "antmicro-footprints:R_0402_1005Metric"
		(layer "B.Cu")
		(at 71.24 147.925 180)
		(descr "Resistor SMD 0402")
		(tags "resistor SMD 0402")
		(property "Reference" "R24"
			(at 0.74 -0.375 0)
			(layer "B.SilkS")
			(effects
				(font
					(size 0.7 0.7)
					(thickness 0.15)
				)
				(justify left bottom mirror)
			)
		)
		(property "Value" "R_4k7_0402"
			(at 0 -1.4 0)
			(layer "B.Fab")
			(effects
				(font
					(size 0.7 0.7)
					(thickness 0.15)
				)
				(justify left bottom mirror)
			)
		)
		(property "Datasheet" "https://www.bourns.com/docs/product-datasheets/cr.pdf"
			(at 0 0 180)
			(layer "F.Fab")
			(hide yes)
			(effects
				(font
					(size 1.27 1.27)
					(thickness 0.15)
				)
			)
		)
		(property "Description" "SMD Chip Resistor, 4.7 kohm, ± 1%, 62.5 mW, 0402 [1005 Metric], Thick Film, General Purpose"
			(at 0 0 180)
			(layer "F.Fab")
			(hide yes)
			(effects
				(font
					(size 1.27 1.27)
					(thickness 0.15)
				)
			)
		)
		(property "Author" "Antmicro"
			(at 142.48 295.85 0)
			(layer "B.Fab")
			(hide yes)
			(effects
				(font
					(size 1 1)
					(thickness 0.15)
				)
				(justify mirror)
			)
		)
		(property "License" "Apache-2.0"
			(at 142.48 295.85 0)
			(layer "B.Fab")
			(hide yes)
			(effects
				(font
					(size 1 1)
					(thickness 0.15)
				)
				(justify mirror)
			)
		)
		(property "MPN" "CR0402-FX-4701GLF"
			(at 142.48 295.85 0)
			(layer "B.Fab")
			(hide yes)
			(effects
				(font
					(size 1 1)
					(thickness 0.15)
				)
				(justify mirror)
			)
		)
		(property "Manufacturer" "Bourns"
			(at 142.48 295.85 0)
			(layer "B.Fab")
			(hide yes)
			(effects
				(font
					(size 1 1)
					(thickness 0.15)
				)
				(justify mirror)
			)
		)
		(property "Tolerance" "1%"
			(at 142.48 295.85 0)
			(layer "B.Fab")
			(hide yes)
			(effects
				(font
					(size 1 1)
					(thickness 0.15)
				)
				(justify mirror)
			)
		)
		(property "Val" "4k7"
			(at 142.48 295.85 0)
			(layer "B.Fab")
			(hide yes)
			(effects
				(font
					(size 1 1)
					(thickness 0.15)
				)
				(justify mirror)
			)
		)
		(sheetname "/RoT/")
		(sheetfile "rot.kicad_sch")
		(attr smd)
		(fp_rect
			(start -0.925 0.47)
			(end 0.925 -0.47)
			(stroke
				(width 0.05)
				(type default)
			)
			(fill no)
			(layer "B.CrtYd")
		)
		(fp_rect
			(start -0.5 0.25)
			(end 0.5 -0.25)
			(stroke
				(width 0.15)
				(type solid)
			)
			(fill no)
			(layer "B.Fab")
		)
		(pad "1" smd roundrect
			(at -0.48 0 180)
			(size 0.59 0.64)
			(layers "B.Cu" "B.Mask" "B.Paste")
			(roundrect_rratio 0.25)
			(net 2 "VCC3V3")
			(pintype "passive")
		)
		(pad "2" smd roundrect
			(at 0.48 0 180)
			(size 0.59 0.64)
			(layers "B.Cu" "B.Mask" "B.Paste")
			(roundrect_rratio 0.25)
			(net 135 "QSPIA1_CS_N")
			(pintype "passive")
		)
	)
	(footprint "antmicro-footprints:R_0402_1005Metric"
		(layer "B.Cu")
		(at 71.15 128.675 180)
		(descr "Resistor SMD 0402")
		(tags "resistor SMD 0402")
		(property "Reference" "R22"
			(at 0.75 -0.425 0)
			(layer "B.SilkS")
			(effects
				(font
					(size 0.7 0.7)
					(thickness 0.15)
				)
				(justify left bottom mirror)
			)
		)
		(property "Value" "R_4k7_0402"
			(at 0 -1.4 0)
			(layer "B.Fab")
			(effects
				(font
					(size 0.7 0.7)
					(thickness 0.15)
				)
				(justify left bottom mirror)
			)
		)
		(property "Datasheet" "https://www.bourns.com/docs/product-datasheets/cr.pdf"
			(at 0 0 180)
			(layer "F.Fab")
			(hide yes)
			(effects
				(font
					(size 1.27 1.27)
					(thickness 0.15)
				)
			)
		)
		(property "Description" "SMD Chip Resistor, 4.7 kohm, ± 1%, 62.5 mW, 0402 [1005 Metric], Thick Film, General Purpose"
			(at 0 0 180)
			(layer "F.Fab")
			(hide yes)
			(effects
				(font
					(size 1.27 1.27)
					(thickness 0.15)
				)
			)
		)
		(property "Author" "Antmicro"
			(at 142.3 257.35 0)
			(layer "B.Fab")
			(hide yes)
			(effects
				(font
					(size 1 1)
					(thickness 0.15)
				)
				(justify mirror)
			)
		)
		(property "License" "Apache-2.0"
			(at 142.3 257.35 0)
			(layer "B.Fab")
			(hide yes)
			(effects
				(font
					(size 1 1)
					(thickness 0.15)
				)
				(justify mirror)
			)
		)
		(property "MPN" "CR0402-FX-4701GLF"
			(at 142.3 257.35 0)
			(layer "B.Fab")
			(hide yes)
			(effects
				(font
					(size 1 1)
					(thickness 0.15)
				)
				(justify mirror)
			)
		)
		(property "Manufacturer" "Bourns"
			(at 142.3 257.35 0)
			(layer "B.Fab")
			(hide yes)
			(effects
				(font
					(size 1 1)
					(thickness 0.15)
				)
				(justify mirror)
			)
		)
		(property "Tolerance" "1%"
			(at 142.3 257.35 0)
			(layer "B.Fab")
			(hide yes)
			(effects
				(font
					(size 1 1)
					(thickness 0.15)
				)
				(justify mirror)
			)
		)
		(property "Val" "4k7"
			(at 142.3 257.35 0)
			(layer "B.Fab")
			(hide yes)
			(effects
				(font
					(size 1 1)
					(thickness 0.15)
				)
				(justify mirror)
			)
		)
		(sheetname "/RoT/")
		(sheetfile "rot.kicad_sch")
		(attr smd)
		(fp_rect
			(start -0.925 0.47)
			(end 0.925 -0.47)
			(stroke
				(width 0.05)
				(type default)
			)
			(fill no)
			(layer "B.CrtYd")
		)
		(fp_rect
			(start -0.5 0.25)
			(end 0.5 -0.25)
			(stroke
				(width 0.15)
				(type solid)
			)
			(fill no)
			(layer "B.Fab")
		)
		(pad "1" smd roundrect
			(at -0.48 0 180)
			(size 0.59 0.64)
			(layers "B.Cu" "B.Mask" "B.Paste")
			(roundrect_rratio 0.25)
			(net 2 "VCC3V3")
			(pintype "passive")
		)
		(pad "2" smd roundrect
			(at 0.48 0 180)
			(size 0.59 0.64)
			(layers "B.Cu" "B.Mask" "B.Paste")
			(roundrect_rratio 0.25)
			(net 124 "QSPIB1_CS_N")
			(pintype "passive")
		)
	)
	(footprint "antmicro-footprints:R_0402_1005Metric"
		(layer "B.Cu")
		(at 71.24 148.925)
		(descr "Resistor SMD 0402")
		(tags "resistor SMD 0402")
		(property "Reference" "R44"
			(at -2.95 0.425 0)
			(layer "B.SilkS")
			(effects
				(font
					(size 0.7 0.7)
					(thickness 0.15)
				)
				(justify right bottom mirror)
			)
		)
		(property "Value" "R_10k_0402"
			(at 0 -1.4 0)
			(layer "B.Fab")
			(effects
				(font
					(size 0.7 0.7)
					(thickness 0.15)
				)
				(justify right bottom mirror)
			)
		)
		(property "Datasheet" "https://www.bourns.com/docs/product-datasheets/cr.pdf"
			(at 0 0 0)
			(layer "F.Fab")
			(hide yes)
			(effects
				(font
					(size 1.27 1.27)
					(thickness 0.15)
				)
			)
		)
		(property "Description" "SMD Chip Resistor, 10 kohm, ± 1%, 62.5 mW, 0402 [1005 Metric], Thick Film, General Purpose"
			(at 0 0 0)
			(layer "F.Fab")
			(hide yes)
			(effects
				(font
					(size 1.27 1.27)
					(thickness 0.15)
				)
			)
		)
		(property "Author" "Antmicro"
			(at 0 0 0)
			(layer "B.Fab")
			(hide yes)
			(effects
				(font
					(size 1 1)
					(thickness 0.15)
				)
				(justify mirror)
			)
		)
		(property "License" "Apache-2.0"
			(at 0 0 0)
			(layer "B.Fab")
			(hide yes)
			(effects
				(font
					(size 1 1)
					(thickness 0.15)
				)
				(justify mirror)
			)
		)
		(property "MPN" "CR0402-FX-1002GLF"
			(at 0 0 0)
			(layer "B.Fab")
			(hide yes)
			(effects
				(font
					(size 1 1)
					(thickness 0.15)
				)
				(justify mirror)
			)
		)
		(property "Manufacturer" "Bourns"
			(at 0 0 0)
			(layer "B.Fab")
			(hide yes)
			(effects
				(font
					(size 1 1)
					(thickness 0.15)
				)
				(justify mirror)
			)
		)
		(property "Tolerance" "1%"
			(at 0 0 0)
			(layer "B.Fab")
			(hide yes)
			(effects
				(font
					(size 1 1)
					(thickness 0.15)
				)
				(justify mirror)
			)
		)
		(property "Val" "10k"
			(at 0 0 0)
			(layer "B.Fab")
			(hide yes)
			(effects
				(font
					(size 1 1)
					(thickness 0.15)
				)
				(justify mirror)
			)
		)
		(sheetname "/RoT/")
		(sheetfile "rot.kicad_sch")
		(attr smd)
		(fp_rect
			(start -0.925 0.47)
			(end 0.925 -0.47)
			(stroke
				(width 0.05)
				(type default)
			)
			(fill no)
			(layer "B.CrtYd")
		)
		(fp_rect
			(start -0.5 0.25)
			(end 0.5 -0.25)
			(stroke
				(width 0.15)
				(type solid)
			)
			(fill no)
			(layer "B.Fab")
		)
		(pad "1" smd roundrect
			(at -0.48 0)
			(size 0.59 0.64)
			(layers "B.Cu" "B.Mask" "B.Paste")
			(roundrect_rratio 0.25)
			(net 132 "QSPIA1_D1")
			(pintype "passive")
		)
		(pad "2" smd roundrect
			(at 0.48 0)
			(size 0.59 0.64)
			(layers "B.Cu" "B.Mask" "B.Paste")
			(roundrect_rratio 0.25)
			(net 2 "VCC3V3")
			(pintype "passive")
		)
	)
	(footprint "antmicro-footprints:R_0402_1005Metric"
		(layer "B.Cu")
		(at 71.15 129.675)
		(descr "Resistor SMD 0402")
		(tags "resistor SMD 0402")
		(property "Reference" "R42"
			(at -2.95 0.425 0)
			(layer "B.SilkS")
			(effects
				(font
					(size 0.7 0.7)
					(thickness 0.15)
				)
				(justify right bottom mirror)
			)
		)
		(property "Value" "R_10k_0402"
			(at 0 -1.4 0)
			(layer "B.Fab")
			(effects
				(font
					(size 0.7 0.7)
					(thickness 0.15)
				)
				(justify right bottom mirror)
			)
		)
		(property "Datasheet" "https://www.bourns.com/docs/product-datasheets/cr.pdf"
			(at 0 0 0)
			(layer "F.Fab")
			(hide yes)
			(effects
				(font
					(size 1.27 1.27)
					(thickness 0.15)
				)
			)
		)
		(property "Description" "SMD Chip Resistor, 10 kohm, ± 1%, 62.5 mW, 0402 [1005 Metric], Thick Film, General Purpose"
			(at 0 0 0)
			(layer "F.Fab")
			(hide yes)
			(effects
				(font
					(size 1.27 1.27)
					(thickness 0.15)
				)
			)
		)
		(property "Author" "Antmicro"
			(at 0 0 0)
			(layer "B.Fab")
			(hide yes)
			(effects
				(font
					(size 1 1)
					(thickness 0.15)
				)
				(justify mirror)
			)
		)
		(property "License" "Apache-2.0"
			(at 0 0 0)
			(layer "B.Fab")
			(hide yes)
			(effects
				(font
					(size 1 1)
					(thickness 0.15)
				)
				(justify mirror)
			)
		)
		(property "MPN" "CR0402-FX-1002GLF"
			(at 0 0 0)
			(layer "B.Fab")
			(hide yes)
			(effects
				(font
					(size 1 1)
					(thickness 0.15)
				)
				(justify mirror)
			)
		)
		(property "Manufacturer" "Bourns"
			(at 0 0 0)
			(layer "B.Fab")
			(hide yes)
			(effects
				(font
					(size 1 1)
					(thickness 0.15)
				)
				(justify mirror)
			)
		)
		(property "Tolerance" "1%"
			(at 0 0 0)
			(layer "B.Fab")
			(hide yes)
			(effects
				(font
					(size 1 1)
					(thickness 0.15)
				)
				(justify mirror)
			)
		)
		(property "Val" "10k"
			(at 0 0 0)
			(layer "B.Fab")
			(hide yes)
			(effects
				(font
					(size 1 1)
					(thickness 0.15)
				)
				(justify mirror)
			)
		)
		(sheetname "/RoT/")
		(sheetfile "rot.kicad_sch")
		(attr smd)
		(fp_rect
			(start -0.925 0.47)
			(end 0.925 -0.47)
			(stroke
				(width 0.05)
				(type default)
			)
			(fill no)
			(layer "B.CrtYd")
		)
		(fp_rect
			(start -0.5 0.25)
			(end 0.5 -0.25)
			(stroke
				(width 0.15)
				(type solid)
			)
			(fill no)
			(layer "B.Fab")
		)
		(pad "1" smd roundrect
			(at -0.48 0)
			(size 0.59 0.64)
			(layers "B.Cu" "B.Mask" "B.Paste")
			(roundrect_rratio 0.25)
			(net 121 "QSPIB1_D1")
			(pintype "passive")
		)
		(pad "2" smd roundrect
			(at 0.48 0)
			(size 0.59 0.64)
			(layers "B.Cu" "B.Mask" "B.Paste")
			(roundrect_rratio 0.25)
			(net 2 "VCC3V3")
			(pintype "passive")
		)
	)
	(footprint "antmicro-footprints:R_0402_1005Metric"
		(layer "B.Cu")
		(at 71.24 146.925)
		(descr "Resistor SMD 0402")
		(tags "resistor SMD 0402")
		(property "Reference" "R40"
			(at -2.95 0.425 0)
			(layer "B.SilkS")
			(effects
				(font
					(size 0.7 0.7)
					(thickness 0.15)
				)
				(justify right bottom mirror)
			)
		)
		(property "Value" "R_10k_0402"
			(at 0 -1.4 0)
			(layer "B.Fab")
			(effects
				(font
					(size 0.7 0.7)
					(thickness 0.15)
				)
				(justify right bottom mirror)
			)
		)
		(property "Datasheet" "https://www.bourns.com/docs/product-datasheets/cr.pdf"
			(at 0 0 0)
			(layer "F.Fab")
			(hide yes)
			(effects
				(font
					(size 1.27 1.27)
					(thickness 0.15)
				)
			)
		)
		(property "Description" "SMD Chip Resistor, 10 kohm, ± 1%, 62.5 mW, 0402 [1005 Metric], Thick Film, General Purpose"
			(at 0 0 0)
			(layer "F.Fab")
			(hide yes)
			(effects
				(font
					(size 1.27 1.27)
					(thickness 0.15)
				)
			)
		)
		(property "Author" "Antmicro"
			(at 0 0 0)
			(layer "B.Fab")
			(hide yes)
			(effects
				(font
					(size 1 1)
					(thickness 0.15)
				)
				(justify mirror)
			)
		)
		(property "License" "Apache-2.0"
			(at 0 0 0)
			(layer "B.Fab")
			(hide yes)
			(effects
				(font
					(size 1 1)
					(thickness 0.15)
				)
				(justify mirror)
			)
		)
		(property "MPN" "CR0402-FX-1002GLF"
			(at 0 0 0)
			(layer "B.Fab")
			(hide yes)
			(effects
				(font
					(size 1 1)
					(thickness 0.15)
				)
				(justify mirror)
			)
		)
		(property "Manufacturer" "Bourns"
			(at 0 0 0)
			(layer "B.Fab")
			(hide yes)
			(effects
				(font
					(size 1 1)
					(thickness 0.15)
				)
				(justify mirror)
			)
		)
		(property "Tolerance" "1%"
			(at 0 0 0)
			(layer "B.Fab")
			(hide yes)
			(effects
				(font
					(size 1 1)
					(thickness 0.15)
				)
				(justify mirror)
			)
		)
		(property "Val" "10k"
			(at 0 0 0)
			(layer "B.Fab")
			(hide yes)
			(effects
				(font
					(size 1 1)
					(thickness 0.15)
				)
				(justify mirror)
			)
		)
		(sheetname "/RoT/")
		(sheetfile "rot.kicad_sch")
		(attr smd)
		(fp_rect
			(start -0.925 0.47)
			(end 0.925 -0.47)
			(stroke
				(width 0.05)
				(type default)
			)
			(fill no)
			(layer "B.CrtYd")
		)
		(fp_rect
			(start -0.5 0.25)
			(end 0.5 -0.25)
			(stroke
				(width 0.15)
				(type solid)
			)
			(fill no)
			(layer "B.Fab")
		)
		(pad "1" smd roundrect
			(at -0.48 0)
			(size 0.59 0.64)
			(layers "B.Cu" "B.Mask" "B.Paste")
			(roundrect_rratio 0.25)
			(net 134 "QSPIA1_D3")
			(pintype "passive")
		)
		(pad "2" smd roundrect
			(at 0.48 0)
			(size 0.59 0.64)
			(layers "B.Cu" "B.Mask" "B.Paste")
			(roundrect_rratio 0.25)
			(net 2 "VCC3V3")
			(pintype "passive")
		)
	)
	(footprint "antmicro-footprints:R_0402_1005Metric"
		(layer "B.Cu")
		(at 71.15 127.675)
		(descr "Resistor SMD 0402")
		(tags "resistor SMD 0402")
		(property "Reference" "R38"
			(at -2.95 0.425 0)
			(layer "B.SilkS")
			(effects
				(font
					(size 0.7 0.7)
					(thickness 0.15)
				)
				(justify right bottom mirror)
			)
		)
		(property "Value" "R_10k_0402"
			(at 0 -1.4 0)
			(layer "B.Fab")
			(effects
				(font
					(size 0.7 0.7)
					(thickness 0.15)
				)
				(justify right bottom mirror)
			)
		)
		(property "Datasheet" "https://www.bourns.com/docs/product-datasheets/cr.pdf"
			(at 0 0 0)
			(layer "F.Fab")
			(hide yes)
			(effects
				(font
					(size 1.27 1.27)
					(thickness 0.15)
				)
			)
		)
		(property "Description" "SMD Chip Resistor, 10 kohm, ± 1%, 62.5 mW, 0402 [1005 Metric], Thick Film, General Purpose"
			(at 0 0 0)
			(layer "F.Fab")
			(hide yes)
			(effects
				(font
					(size 1.27 1.27)
					(thickness 0.15)
				)
			)
		)
		(property "Author" "Antmicro"
			(at 0 0 0)
			(layer "B.Fab")
			(hide yes)
			(effects
				(font
					(size 1 1)
					(thickness 0.15)
				)
				(justify mirror)
			)
		)
		(property "License" "Apache-2.0"
			(at 0 0 0)
			(layer "B.Fab")
			(hide yes)
			(effects
				(font
					(size 1 1)
					(thickness 0.15)
				)
				(justify mirror)
			)
		)
		(property "MPN" "CR0402-FX-1002GLF"
			(at 0 0 0)
			(layer "B.Fab")
			(hide yes)
			(effects
				(font
					(size 1 1)
					(thickness 0.15)
				)
				(justify mirror)
			)
		)
		(property "Manufacturer" "Bourns"
			(at 0 0 0)
			(layer "B.Fab")
			(hide yes)
			(effects
				(font
					(size 1 1)
					(thickness 0.15)
				)
				(justify mirror)
			)
		)
		(property "Tolerance" "1%"
			(at 0 0 0)
			(layer "B.Fab")
			(hide yes)
			(effects
				(font
					(size 1 1)
					(thickness 0.15)
				)
				(justify mirror)
			)
		)
		(property "Val" "10k"
			(at 0 0 0)
			(layer "B.Fab")
			(hide yes)
			(effects
				(font
					(size 1 1)
					(thickness 0.15)
				)
				(justify mirror)
			)
		)
		(sheetname "/RoT/")
		(sheetfile "rot.kicad_sch")
		(attr smd)
		(fp_rect
			(start -0.925 0.47)
			(end 0.925 -0.47)
			(stroke
				(width 0.05)
				(type default)
			)
			(fill no)
			(layer "B.CrtYd")
		)
		(fp_rect
			(start -0.5 0.25)
			(end 0.5 -0.25)
			(stroke
				(width 0.15)
				(type solid)
			)
			(fill no)
			(layer "B.Fab")
		)
		(pad "1" smd roundrect
			(at -0.48 0)
			(size 0.59 0.64)
			(layers "B.Cu" "B.Mask" "B.Paste")
			(roundrect_rratio 0.25)
			(net 123 "QSPIB1_D3")
			(pintype "passive")
		)
		(pad "2" smd roundrect
			(at 0.48 0)
			(size 0.59 0.64)
			(layers "B.Cu" "B.Mask" "B.Paste")
			(roundrect_rratio 0.25)
			(net 2 "VCC3V3")
			(pintype "passive")
		)
	)
)
